(kicad_pcb
	(version 20260206)
	(generator "pcbnew")
	(generator_version "10.0")
	(general
		(thickness 1.6)
		(legacy_teardrops no)
	)
	(paper "A4")
	(title_block
		(title "04192023_DAF0TMB3IC0_F0TG_MB_C_brd_V02_OCP.brd")
		(comment 1 "Grand Teton / footprints 5036-5044 of 8354")
	)
	(layers
		(0 "F.Cu" signal "TOP")
		(4 "In1.Cu" signal "GND")
		(6 "In2.Cu" signal "IN1")
		(8 "In3.Cu" signal "GND1")
		(10 "In4.Cu" signal "IN2")
		(12 "In5.Cu" signal "GND2")
		(14 "In6.Cu" signal "IN3")
		(16 "In7.Cu" signal "GND3")
		(18 "In8.Cu" signal "VCC")
		(20 "In9.Cu" signal "VCC1")
		(22 "In10.Cu" signal "GND4")
		(24 "In11.Cu" signal "IN4")
		(26 "In12.Cu" signal "GND5")
		(28 "In13.Cu" signal "IN5")
		(30 "In14.Cu" signal "GND6")
		(32 "In15.Cu" signal "IN6")
		(34 "In16.Cu" signal "GND7")
		(2 "B.Cu" signal "BOTTOM")
		(9 "F.Adhes" user "F.Adhesive")
		(11 "B.Adhes" user "B.Adhesive")
		(13 "F.Paste" user "Package Geometry/Pastemask Top")
		(15 "B.Paste" user "Package Geometry/Pastemask Bottom")
		(5 "F.SilkS" user "Ref Des/Silkscreen Top")
		(7 "B.SilkS" user "Ref Des/Silkscreen Bottom")
		(1 "F.Mask" user "Board Geometry/Soldermask Top")
		(3 "B.Mask" user "Board Geometry/Soldermask Bottom")
		(17 "Dwgs.User" user "User.Drawings")
		(19 "Cmts.User" user "User.Comments")
		(21 "Eco1.User" user "User.Eco1")
		(23 "Eco2.User" user "User.Eco2")
		(25 "Edge.Cuts" user "Board Geometry/Outline")
		(27 "Margin" user)
		(31 "F.CrtYd" user "Package Geometry/Place Bound Top")
		(29 "B.CrtYd" user "Package Geometry/Place Bound Bottom")
		(35 "F.Fab" user "Ref Des/Assembly Top")
		(33 "B.Fab" user "Ref Des/Assembly Bottom")
	)
	(footprint ""
		(layer "B.Cu")
		(at 115.70589 -259.845302 180)
		(property "Reference" "C2488"
			(at 0 0 0)
			(layer "B.SilkS")
			(hide yes)
			(effects
				(font
					(size 1.27 1.27)
				)
				(justify mirror)
			)
		)
		(property "Value" ""
			(at 0 0 0)
			(layer "B.Fab")
			(effects
				(font
					(size 1.27 1.27)
				)
				(justify mirror)
			)
		)
		(duplicate_pad_numbers_are_jumpers no)
		(fp_line
			(start 0.7874 0.4064)
			(end 0.7874 -0.4064)
			(stroke
				(width 0.1524)
				(type default)
			)
			(layer "B.SilkS")
		)
		(fp_line
			(start 0.7874 -0.4064)
			(end -0.7874 -0.4064)
			(stroke
				(width 0.1524)
				(type default)
			)
			(layer "B.SilkS")
		)
		(fp_line
			(start -0.7874 0.4064)
			(end 0.7874 0.4064)
			(stroke
				(width 0.1524)
				(type default)
			)
			(layer "B.SilkS")
		)
		(fp_line
			(start -0.7874 -0.4064)
			(end -0.7874 0.4064)
			(stroke
				(width 0.1524)
				(type default)
			)
			(layer "B.SilkS")
		)
		(fp_line
			(start 0.67945 0.3048)
			(end 0.67945 -0.305054)
			(stroke
				(width 0.1)
				(type default)
			)
			(layer "B.Fab")
		)
		(fp_line
			(start 0.67945 -0.305054)
			(end 0.12065 -0.305054)
			(stroke
				(width 0.1)
				(type default)
			)
			(layer "B.Fab")
		)
		(fp_line
			(start 0.12065 0.3048)
			(end 0.67945 0.3048)
			(stroke
				(width 0.1)
				(type default)
			)
			(layer "B.Fab")
		)
		(fp_line
			(start 0.12065 0.2794)
			(end 0.12065 0.3048)
			(stroke
				(width 0.1)
				(type default)
			)
			(layer "B.Fab")
		)
		(fp_line
			(start 0.12065 -0.2794)
			(end -0.12065 -0.2794)
			(stroke
				(width 0.1)
				(type default)
			)
			(layer "B.Fab")
		)
		(fp_line
			(start 0.12065 -0.305054)
			(end 0.12065 -0.2794)
			(stroke
				(width 0.1)
				(type default)
			)
			(layer "B.Fab")
		)
		(fp_line
			(start -0.120396 0.3048)
			(end -0.120396 0.2794)
			(stroke
				(width 0.1)
				(type default)
			)
			(layer "B.Fab")
		)
		(fp_line
			(start -0.120396 0.2794)
			(end 0.12065 0.2794)
			(stroke
				(width 0.1)
				(type default)
			)
			(layer "B.Fab")
		)
		(fp_line
			(start -0.12065 -0.2794)
			(end -0.12065 -0.3048)
			(stroke
				(width 0.1)
				(type default)
			)
			(layer "B.Fab")
		)
		(fp_line
			(start -0.12065 -0.3048)
			(end -0.67945 -0.3048)
			(stroke
				(width 0.1)
				(type default)
			)
			(layer "B.Fab")
		)
		(fp_line
			(start -0.67945 0.3048)
			(end -0.120396 0.3048)
			(stroke
				(width 0.1)
				(type default)
			)
			(layer "B.Fab")
		)
		(fp_line
			(start -0.67945 -0.3048)
			(end -0.67945 0.3048)
			(stroke
				(width 0.1)
				(type default)
			)
			(layer "B.Fab")
		)
		(pad "1" smd circle
			(at 0.40005 0)
			(size 0 0)
			(layers "B.Cu" "B.Mask" "B.Paste")
			(net "PVDD11_S3_P1")
		)
		(pad "2" smd circle
			(at -0.40005 0)
			(size 0 0)
			(layers "B.Cu" "B.Mask" "B.Paste")
			(net "GND")
		)
	)
	(footprint ""
		(layer "B.Cu")
		(at 72.052434 -386.745988 -90)
		(property "Reference" "C122"
			(at 0 0 90)
			(layer "B.SilkS")
			(hide yes)
			(effects
				(font
					(size 1.27 1.27)
				)
				(justify mirror)
			)
		)
		(property "Value" ""
			(at 0 0 90)
			(layer "B.Fab")
			(effects
				(font
					(size 1.27 1.27)
				)
				(justify mirror)
			)
		)
		(duplicate_pad_numbers_are_jumpers no)
		(fp_line
			(start -0.7874 0.4064)
			(end 0.7874 0.4064)
			(stroke
				(width 0.1524)
				(type default)
			)
			(layer "B.SilkS")
		)
		(fp_line
			(start 0.7874 0.4064)
			(end 0.7874 -0.4064)
			(stroke
				(width 0.1524)
				(type default)
			)
			(layer "B.SilkS")
		)
		(fp_line
			(start -0.7874 -0.4064)
			(end -0.7874 0.4064)
			(stroke
				(width 0.1524)
				(type default)
			)
			(layer "B.SilkS")
		)
		(fp_line
			(start 0.7874 -0.4064)
			(end -0.7874 -0.4064)
			(stroke
				(width 0.1524)
				(type default)
			)
			(layer "B.SilkS")
		)
		(fp_line
			(start -0.67945 0.3048)
			(end -0.120396 0.3048)
			(stroke
				(width 0.1)
				(type default)
			)
			(layer "B.Fab")
		)
		(fp_line
			(start -0.120396 0.3048)
			(end -0.120396 0.2794)
			(stroke
				(width 0.1)
				(type default)
			)
			(layer "B.Fab")
		)
		(fp_line
			(start 0.12065 0.3048)
			(end 0.67945 0.3048)
			(stroke
				(width 0.1)
				(type default)
			)
			(layer "B.Fab")
		)
		(fp_line
			(start 0.67945 0.3048)
			(end 0.67945 -0.305054)
			(stroke
				(width 0.1)
				(type default)
			)
			(layer "B.Fab")
		)
		(fp_line
			(start -0.120396 0.2794)
			(end 0.12065 0.2794)
			(stroke
				(width 0.1)
				(type default)
			)
			(layer "B.Fab")
		)
		(fp_line
			(start 0.12065 0.2794)
			(end 0.12065 0.3048)
			(stroke
				(width 0.1)
				(type default)
			)
			(layer "B.Fab")
		)
		(fp_line
			(start -0.12065 -0.2794)
			(end -0.12065 -0.3048)
			(stroke
				(width 0.1)
				(type default)
			)
			(layer "B.Fab")
		)
		(fp_line
			(start 0.12065 -0.2794)
			(end -0.12065 -0.2794)
			(stroke
				(width 0.1)
				(type default)
			)
			(layer "B.Fab")
		)
		(fp_line
			(start -0.67945 -0.3048)
			(end -0.67945 0.3048)
			(stroke
				(width 0.1)
				(type default)
			)
			(layer "B.Fab")
		)
		(fp_line
			(start -0.12065 -0.3048)
			(end -0.67945 -0.3048)
			(stroke
				(width 0.1)
				(type default)
			)
			(layer "B.Fab")
		)
		(fp_line
			(start 0.12065 -0.305054)
			(end 0.12065 -0.2794)
			(stroke
				(width 0.1)
				(type default)
			)
			(layer "B.Fab")
		)
		(fp_line
			(start 0.67945 -0.305054)
			(end 0.12065 -0.305054)
			(stroke
				(width 0.1)
				(type default)
			)
			(layer "B.Fab")
		)
		(pad "1" smd circle
			(at 0.40005 0 90)
			(size 0 0)
			(layers "B.Cu" "B.Mask" "B.Paste")
			(net "P1V8_CPU1_RT_1D")
		)
		(pad "2" smd circle
			(at -0.40005 0 90)
			(size 0 0)
			(layers "B.Cu" "B.Mask" "B.Paste")
			(net "GND")
		)
	)
	(footprint ""
		(layer "B.Cu")
		(at 185.496708 -422.208452 90)
		(property "Reference" "R8109"
			(at 0 0 90)
			(layer "B.SilkS")
			(hide yes)
			(effects
				(font
					(size 1.27 1.27)
				)
				(justify mirror)
			)
		)
		(property "Value" ""
			(at 0 0 90)
			(layer "B.Fab")
			(effects
				(font
					(size 1.27 1.27)
				)
				(justify mirror)
			)
		)
		(duplicate_pad_numbers_are_jumpers no)
		(fp_line
			(start 0.7874 -0.4064)
			(end -0.7874 -0.4064)
			(stroke
				(width 0.1524)
				(type default)
			)
			(layer "B.SilkS")
		)
		(fp_line
			(start -0.7874 -0.4064)
			(end -0.7874 0.4064)
			(stroke
				(width 0.1524)
				(type default)
			)
			(layer "B.SilkS")
		)
		(fp_line
			(start 0.7874 0.4064)
			(end 0.7874 -0.4064)
			(stroke
				(width 0.1524)
				(type default)
			)
			(layer "B.SilkS")
		)
		(fp_line
			(start -0.7874 0.4064)
			(end 0.7874 0.4064)
			(stroke
				(width 0.1524)
				(type default)
			)
			(layer "B.SilkS")
		)
		(fp_line
			(start 0.67945 -0.305054)
			(end 0.12065 -0.305054)
			(stroke
				(width 0.1)
				(type default)
			)
			(layer "B.Fab")
		)
		(fp_line
			(start 0.12065 -0.305054)
			(end 0.12065 -0.2794)
			(stroke
				(width 0.1)
				(type default)
			)
			(layer "B.Fab")
		)
		(fp_line
			(start -0.12065 -0.3048)
			(end -0.67945 -0.3048)
			(stroke
				(width 0.1)
				(type default)
			)
			(layer "B.Fab")
		)
		(fp_line
			(start -0.67945 -0.3048)
			(end -0.67945 0.3048)
			(stroke
				(width 0.1)
				(type default)
			)
			(layer "B.Fab")
		)
		(fp_line
			(start 0.12065 -0.2794)
			(end -0.12065 -0.2794)
			(stroke
				(width 0.1)
				(type default)
			)
			(layer "B.Fab")
		)
		(fp_line
			(start -0.12065 -0.2794)
			(end -0.12065 -0.3048)
			(stroke
				(width 0.1)
				(type default)
			)
			(layer "B.Fab")
		)
		(fp_line
			(start 0.12065 0.2794)
			(end 0.12065 0.3048)
			(stroke
				(width 0.1)
				(type default)
			)
			(layer "B.Fab")
		)
		(fp_line
			(start -0.120396 0.2794)
			(end 0.12065 0.2794)
			(stroke
				(width 0.1)
				(type default)
			)
			(layer "B.Fab")
		)
		(fp_line
			(start 0.67945 0.3048)
			(end 0.67945 -0.305054)
			(stroke
				(width 0.1)
				(type default)
			)
			(layer "B.Fab")
		)
		(fp_line
			(start 0.12065 0.3048)
			(end 0.67945 0.3048)
			(stroke
				(width 0.1)
				(type default)
			)
			(layer "B.Fab")
		)
		(fp_line
			(start -0.120396 0.3048)
			(end -0.120396 0.2794)
			(stroke
				(width 0.1)
				(type default)
			)
			(layer "B.Fab")
		)
		(fp_line
			(start -0.67945 0.3048)
			(end -0.120396 0.3048)
			(stroke
				(width 0.1)
				(type default)
			)
			(layer "B.Fab")
		)
		(pad "1" smd circle
			(at 0.40005 0 270)
			(size 0 0)
			(layers "B.Cu" "B.Mask" "B.Paste")
			(net "HSC_OC_VOL")
		)
		(pad "2" smd circle
			(at -0.40005 0 270)
			(size 0 0)
			(layers "B.Cu" "B.Mask" "B.Paste")
			(net "GND")
		)
	)
	(footprint ""
		(layer "B.Cu")
		(at 109.519466 -390.587484)
		(property "Reference" "C479"
			(at 0 0 0)
			(layer "B.SilkS")
			(hide yes)
			(effects
				(font
					(size 1.27 1.27)
				)
				(justify mirror)
			)
		)
		(property "Value" ""
			(at 0 0 0)
			(layer "B.Fab")
			(effects
				(font
					(size 1.27 1.27)
				)
				(justify mirror)
			)
		)
		(duplicate_pad_numbers_are_jumpers no)
		(fp_line
			(start -1.524 -0.762)
			(end -1.524 0.762)
			(stroke
				(width 0.1524)
				(type default)
			)
			(layer "B.SilkS")
		)
		(fp_line
			(start -1.524 0.762)
			(end 1.524 0.762)
			(stroke
				(width 0.1524)
				(type default)
			)
			(layer "B.SilkS")
		)
		(fp_line
			(start 1.524 -0.762)
			(end -1.524 -0.762)
			(stroke
				(width 0.1524)
				(type default)
			)
			(layer "B.SilkS")
		)
		(fp_line
			(start 1.524 0.762)
			(end 1.524 -0.762)
			(stroke
				(width 0.1524)
				(type default)
			)
			(layer "B.SilkS")
		)
		(fp_line
			(start -1.1049 -0.724916)
			(end 1.1049 -0.724916)
			(stroke
				(width 0.1)
				(type default)
			)
			(layer "B.Fab")
		)
		(fp_line
			(start -1.1049 0.724916)
			(end -1.1049 -0.724916)
			(stroke
				(width 0.1)
				(type default)
			)
			(layer "B.Fab")
		)
		(fp_line
			(start 1.1049 -0.724916)
			(end 1.1049 0.724916)
			(stroke
				(width 0.1)
				(type default)
			)
			(layer "B.Fab")
		)
		(fp_line
			(start 1.1049 0.724916)
			(end -1.1049 0.724916)
			(stroke
				(width 0.1)
				(type default)
			)
			(layer "B.Fab")
		)
		(pad "1" smd rect
			(at 0.889 0)
			(size 1.016 1.27)
			(layers "B.Cu" "B.Mask" "B.Paste")
			(net "P0V9_CPU1_RT3_2A")
		)
		(pad "2" smd rect
			(at -0.889 0)
			(size 1.016 1.27)
			(layers "B.Cu" "B.Mask" "B.Paste")
			(net "GND")
		)
	)
	(footprint ""
		(layer "B.Cu")
		(at 306.978304 -395.148562 90)
		(property "Reference" "C581"
			(at 0 0 90)
			(layer "B.SilkS")
			(hide yes)
			(effects
				(font
					(size 1.27 1.27)
				)
				(justify mirror)
			)
		)
		(property "Value" ""
			(at 0 0 90)
			(layer "B.Fab")
			(effects
				(font
					(size 1.27 1.27)
				)
				(justify mirror)
			)
		)
		(duplicate_pad_numbers_are_jumpers no)
		(fp_line
			(start 0.299974 -0.150114)
			(end -0.299974 -0.150114)
			(stroke
				(width 0.1)
				(type default)
			)
			(layer "B.Fab")
		)
		(fp_line
			(start -0.299974 -0.150114)
			(end -0.299974 0.150114)
			(stroke
				(width 0.1)
				(type default)
			)
			(layer "B.Fab")
		)
		(fp_line
			(start 0.299974 0.150114)
			(end 0.299974 -0.150114)
			(stroke
				(width 0.1)
				(type default)
			)
			(layer "B.Fab")
		)
		(fp_line
			(start -0.299974 0.150114)
			(end 0.299974 0.150114)
			(stroke
				(width 0.1)
				(type default)
			)
			(layer "B.Fab")
		)
		(pad "1" smd rect
			(at 0.2667 0 270)
			(size 0.3048 0.381)
			(layers "B.Cu" "B.Mask" "B.Paste")
			(net "P0V9_CPU0_RT0_2A")
		)
		(pad "2" smd rect
			(at -0.2667 0 270)
			(size 0.3048 0.381)
			(layers "B.Cu" "B.Mask" "B.Paste")
			(net "GND")
		)
	)
	(footprint ""
		(layer "B.Cu")
		(at 380.075186 -214.523828 90)
		(property "Reference" "R8564"
			(at 0 0 90)
			(layer "B.SilkS")
			(hide yes)
			(effects
				(font
					(size 1.27 1.27)
				)
				(justify mirror)
			)
		)
		(property "Value" ""
			(at 0 0 90)
			(layer "B.Fab")
			(effects
				(font
					(size 1.27 1.27)
				)
				(justify mirror)
			)
		)
		(duplicate_pad_numbers_are_jumpers no)
		(fp_line
			(start 0.7874 -0.4064)
			(end -0.7874 -0.4064)
			(stroke
				(width 0.1524)
				(type default)
			)
			(layer "B.SilkS")
		)
		(fp_line
			(start -0.7874 -0.4064)
			(end -0.7874 0.010414)
			(stroke
				(width 0.1524)
				(type default)
			)
			(layer "B.SilkS")
		)
		(fp_line
			(start 0.7874 0.035814)
			(end 0.7874 -0.4064)
			(stroke
				(width 0.1524)
				(type default)
			)
			(layer "B.SilkS")
		)
		(fp_line
			(start -0.325628 0.4064)
			(end 0.436372 0.4064)
			(stroke
				(width 0.1524)
				(type default)
			)
			(layer "B.SilkS")
		)
		(fp_line
			(start 0.67945 -0.305054)
			(end 0.12065 -0.305054)
			(stroke
				(width 0.1)
				(type default)
			)
			(layer "B.Fab")
		)
		(fp_line
			(start 0.12065 -0.305054)
			(end 0.12065 -0.2794)
			(stroke
				(width 0.1)
				(type default)
			)
			(layer "B.Fab")
		)
		(fp_line
			(start -0.12065 -0.3048)
			(end -0.67945 -0.3048)
			(stroke
				(width 0.1)
				(type default)
			)
			(layer "B.Fab")
		)
		(fp_line
			(start -0.67945 -0.3048)
			(end -0.67945 0.3048)
			(stroke
				(width 0.1)
				(type default)
			)
			(layer "B.Fab")
		)
		(fp_line
			(start 0.12065 -0.2794)
			(end -0.12065 -0.2794)
			(stroke
				(width 0.1)
				(type default)
			)
			(layer "B.Fab")
		)
		(fp_line
			(start -0.12065 -0.2794)
			(end -0.12065 -0.3048)
			(stroke
				(width 0.1)
				(type default)
			)
			(layer "B.Fab")
		)
		(fp_line
			(start 0.12065 0.2794)
			(end 0.12065 0.3048)
			(stroke
				(width 0.1)
				(type default)
			)
			(layer "B.Fab")
		)
		(fp_line
			(start -0.120396 0.2794)
			(end 0.12065 0.2794)
			(stroke
				(width 0.1)
				(type default)
			)
			(layer "B.Fab")
		)
		(fp_line
			(start 0.67945 0.3048)
			(end 0.67945 -0.305054)
			(stroke
				(width 0.1)
				(type default)
			)
			(layer "B.Fab")
		)
		(fp_line
			(start 0.12065 0.3048)
			(end 0.67945 0.3048)
			(stroke
				(width 0.1)
				(type default)
			)
			(layer "B.Fab")
		)
		(fp_line
			(start -0.120396 0.3048)
			(end -0.120396 0.2794)
			(stroke
				(width 0.1)
				(type default)
			)
			(layer "B.Fab")
		)
		(fp_line
			(start -0.67945 0.3048)
			(end -0.120396 0.3048)
			(stroke
				(width 0.1)
				(type default)
			)
			(layer "B.Fab")
		)
		(pad "1" smd circle
			(at 0.40005 0 270)
			(size 0 0)
			(layers "B.Cu" "B.Mask" "B.Paste")
			(net "CLK_100M_CPU0_CLK02_R_DN")
		)
		(pad "2" smd circle
			(at -0.40005 0 270)
			(size 0 0)
			(layers "B.Cu" "B.Mask" "B.Paste")
			(net "CLK_100M_CPU0_CLK02_DN")
		)
	)
	(footprint ""
		(layer "B.Cu")
		(at 216.916 -337.439 90)
		(property "Reference" "R6739"
			(at 0 0 90)
			(layer "B.SilkS")
			(hide yes)
			(effects
				(font
					(size 1.27 1.27)
				)
				(justify mirror)
			)
		)
		(property "Value" ""
			(at 0 0 90)
			(layer "B.Fab")
			(effects
				(font
					(size 1.27 1.27)
				)
				(justify mirror)
			)
		)
		(duplicate_pad_numbers_are_jumpers no)
		(fp_line
			(start 0.32512 -0.175006)
			(end -0.32512 -0.175006)
			(stroke
				(width 0.1)
				(type default)
			)
			(layer "B.Fab")
		)
		(fp_line
			(start -0.32512 -0.175006)
			(end -0.32512 0.175006)
			(stroke
				(width 0.1)
				(type default)
			)
			(layer "B.Fab")
		)
		(fp_line
			(start 0.32512 0.175006)
			(end 0.32512 -0.175006)
			(stroke
				(width 0.1)
				(type default)
			)
			(layer "B.Fab")
		)
		(fp_line
			(start -0.32512 0.175006)
			(end 0.32512 0.175006)
			(stroke
				(width 0.1)
				(type default)
			)
			(layer "B.Fab")
		)
		(pad "1" smd rect
			(at 0.2667 0 270)
			(size 0.3048 0.381)
			(layers "B.Cu" "B.Mask" "B.Paste")
			(net "P1V8_CPU1_RT_1D")
		)
		(pad "2" smd rect
			(at -0.2667 0 90)
			(size 0.3048 0.381)
			(layers "B.Cu" "B.Mask" "B.Paste")
			(net "SMB_RT_CPU1_P1_R_SCL")
		)
	)
	(footprint ""
		(layer "B.Cu")
		(at 306.7304 -354.076 180)
		(property "Reference" "TP6"
			(at 0.69088 -0.114554 0)
			(unlocked yes)
			(layer "B.SilkS")
			(effects
				(font
					(size 0.7874 0.5842)
					(thickness 0.1524)
				)
				(justify left mirror)
			)
		)
		(property "Value" ""
			(at 0 0 0)
			(layer "B.Fab")
			(effects
				(font
					(size 1.27 1.27)
				)
				(justify mirror)
			)
		)
		(duplicate_pad_numbers_are_jumpers no)
		(pad "1" smd circle
			(at 0 0)
			(size 0.762 0.762)
			(layers "B.Cu" "B.Mask" "B.Paste")
			(net "VSENSE_PVDDCR_CPU1_P0_DP")
		)
	)
	(footprint ""
		(layer "B.Cu")
		(at 73.806304 -408.517344 90)
		(property "Reference" "C6678"
			(at 0 0 90)
			(layer "B.SilkS")
			(hide yes)
			(effects
				(font
					(size 1.27 1.27)
				)
				(justify mirror)
			)
		)
		(property "Value" ""
			(at 0 0 90)
			(layer "B.Fab")
			(effects
				(font
					(size 1.27 1.27)
				)
				(justify mirror)
			)
		)
		(duplicate_pad_numbers_are_jumpers no)
		(fp_line
			(start 0.299974 -0.150114)
			(end -0.299974 -0.150114)
			(stroke
				(width 0.1)
				(type default)
			)
			(layer "B.Fab")
		)
		(fp_line
			(start -0.299974 -0.150114)
			(end -0.299974 0.150114)
			(stroke
				(width 0.1)
				(type default)
			)
			(layer "B.Fab")
		)
		(fp_line
			(start 0.299974 0.150114)
			(end 0.299974 -0.150114)
			(stroke
				(width 0.1)
				(type default)
			)
			(layer "B.Fab")
		)
		(fp_line
			(start -0.299974 0.150114)
			(end 0.299974 0.150114)
			(stroke
				(width 0.1)
				(type default)
			)
			(layer "B.Fab")
		)
		(pad "1" smd rect
			(at 0.2667 0 270)
			(size 0.3048 0.381)
			(layers "B.Cu" "B.Mask" "B.Paste")
			(net "P5E_CPU1_P1_TX_BUF_C_DN<8>")
		)
		(pad "2" smd rect
			(at -0.2667 0 270)
			(size 0.3048 0.381)
			(layers "B.Cu" "B.Mask" "B.Paste")
			(net "P5E_CPU1_P1_TX_BUF_DN<8>")
		)
	)
)
